(kicad_pcb
	(version 20260206)
	(generator "pcbnew")
	(generator_version "10.0")
	(general
		(thickness 1.6)
		(legacy_teardrops no)
	)
	(paper "A4")
	(title_block
		(title "netronome-mezz — pcbd0082-001_rev01_jul9_a.brd")
		(comment 1 "Open CloudServer (Microsoft) / footprints 175-181 of 714")
	)
	(layers
		(0 "F.Cu" signal "TOP")
		(4 "In1.Cu" signal "02_GND")
		(6 "In2.Cu" signal "03_SIG")
		(8 "In3.Cu" signal "04_SIG")
		(10 "In4.Cu" signal "05_GND")
		(12 "In5.Cu" signal "06_PWR1")
		(14 "In6.Cu" signal "07_SIG")
		(16 "In7.Cu" signal "08_SIG")
		(18 "In8.Cu" signal "09_GND")
		(2 "B.Cu" signal "BOTTOM")
		(9 "F.Adhes" user "F.Adhesive")
		(11 "B.Adhes" user "B.Adhesive")
		(13 "F.Paste" user "Package Geometry/Pastemask Top")
		(15 "B.Paste" user "Package Geometry/Pastemask Bottom")
		(5 "F.SilkS" user "Ref Des/Silkscreen Top")
		(7 "B.SilkS" user "Ref Des/Silkscreen Bottom")
		(1 "F.Mask" user "Board Geometry/Soldermask Top")
		(3 "B.Mask" user "Board Geometry/Soldermask Bottom")
		(17 "Dwgs.User" user "User.Drawings")
		(19 "Cmts.User" user "User.Comments")
		(21 "Eco1.User" user "User.Eco1")
		(23 "Eco2.User" user "User.Eco2")
		(25 "Edge.Cuts" user "Board Geometry/Outline")
		(27 "Margin" user)
		(31 "F.CrtYd" user "Package Geometry/Place Bound Top")
		(29 "B.CrtYd" user "Package Geometry/Place Bound Bottom")
		(35 "F.Fab" user "Ref Des/Assembly Top")
		(33 "B.Fab" user "Ref Des/Assembly Bottom")
		(45 "User.4" user "COMPVAL_TYPE_BOTTOM")
	)
	(footprint ""
		(layer "F.Cu")
		(at 81.915 26.924)
		(property "Reference" "R206"
			(at 0 0 0)
			(layer "F.SilkS")
			(hide yes)
			(effects
				(font
					(size 1.27 1.27)
				)
			)
		)
		(property "Value" "39.0"
			(at -0.148158 1.3462 90)
			(unlocked yes)
			(layer "F.Fab")
			(hide yes)
			(effects
				(font
					(size 1.27 0.9652)
					(thickness 0.000001)
				)
				(justify left)
			)
		)
		(property "Device Type" "REST0108"
			(at -0.148158 1.3462 90)
			(unlocked yes)
			(layer "F.Fab")
			(hide yes)
			(effects
				(font
					(size 1.27 0.9652)
					(thickness 0.000001)
				)
				(justify left)
			)
		)
		(duplicate_pad_numbers_are_jumpers no)
		(fp_poly
			(pts
				(xy 0.635 1.0668) (xy 0.635 -1.0668) (xy -0.635 -1.0668) (xy -0.635 1.0668)
			)
			(stroke
				(width 0)
				(type default)
			)
			(fill no)
			(layer "F.CrtYd")
		)
		(fp_line
			(start -0.254 -0.508)
			(end 0.254 -0.508)
			(stroke
				(width 0.0254)
				(type default)
			)
			(layer "F.Fab")
		)
		(fp_line
			(start -0.254 0.508)
			(end -0.254 -0.508)
			(stroke
				(width 0.0254)
				(type default)
			)
			(layer "F.Fab")
		)
		(fp_line
			(start 0.254 -0.508)
			(end 0.254 0.508)
			(stroke
				(width 0.0254)
				(type default)
			)
			(layer "F.Fab")
		)
		(fp_line
			(start 0.254 0.508)
			(end -0.254 0.508)
			(stroke
				(width 0.0254)
				(type default)
			)
			(layer "F.Fab")
		)
		(pad "1" smd rect
			(at 0 -0.4191)
			(size 0.508 0.5334)
			(layers "F.Cu" "F.Mask" "F.Paste")
			(net "DDR0_32A_A0")
		)
		(pad "2" smd rect
			(at 0 0.4191)
			(size 0.508 0.5334)
			(layers "F.Cu" "F.Mask" "F.Paste")
			(net "DDR_VTT")
		)
		(zone
			(layer "F.Cu")
			(hatch none 0.5)
			(connect_pads
				(clearance 0)
			)
			(min_thickness 0.25)
			(keepout
				(tracks not_allowed)
				(vias allowed)
				(pads allowed)
				(copperpour not_allowed)
				(footprints allowed)
			)
			(placement
				(enabled no)
				(sheetname "")
			)
			(fill
				(thermal_gap 0.5)
				(thermal_bridge_width 0.5)
				(island_removal_mode 0)
			)
			(polygon
				(pts
					(xy 81.9404 26.8986) (xy 81.9404 26.9494) (xy 81.8896 26.9494) (xy 81.8896 26.8986)
				)
			)
		)
	)
	(footprint ""
		(layer "F.Cu")
		(at 78.867 20.574 90)
		(property "Reference" "R352"
			(at 0.73533 -1.651 0)
			(unlocked yes)
			(layer "F.SilkS")
			(effects
				(font
					(size 0.7874 0.5842)
					(thickness 0.127)
				)
				(justify left)
			)
		)
		(property "Value" "240"
			(at -0.148158 1.3462 180)
			(unlocked yes)
			(layer "F.Fab")
			(hide yes)
			(effects
				(font
					(size 1.27 0.9652)
					(thickness 0.000001)
				)
				(justify left)
			)
		)
		(property "Device Type" "REST0009"
			(at -0.148158 1.3462 180)
			(unlocked yes)
			(layer "F.Fab")
			(hide yes)
			(effects
				(font
					(size 1.27 0.9652)
					(thickness 0.000001)
				)
				(justify left)
			)
		)
		(duplicate_pad_numbers_are_jumpers no)
		(fp_poly
			(pts
				(xy 0.635 1.0668) (xy 0.635 -1.0668) (xy -0.635 -1.0668) (xy -0.635 1.0668)
			)
			(stroke
				(width 0)
				(type default)
			)
			(fill no)
			(layer "F.CrtYd")
		)
		(fp_line
			(start 0.254 -0.508)
			(end 0.254 0.508)
			(stroke
				(width 0.0254)
				(type default)
			)
			(layer "F.Fab")
		)
		(fp_line
			(start -0.254 -0.508)
			(end 0.254 -0.508)
			(stroke
				(width 0.0254)
				(type default)
			)
			(layer "F.Fab")
		)
		(fp_line
			(start 0.254 0.508)
			(end -0.254 0.508)
			(stroke
				(width 0.0254)
				(type default)
			)
			(layer "F.Fab")
		)
		(fp_line
			(start -0.254 0.508)
			(end -0.254 -0.508)
			(stroke
				(width 0.0254)
				(type default)
			)
			(layer "F.Fab")
		)
		(pad "1" smd rect
			(at 0 -0.4191 90)
			(size 0.508 0.5334)
			(layers "F.Cu" "F.Mask" "F.Paste")
			(net "GND")
		)
		(pad "2" smd rect
			(at 0 0.4191 90)
			(size 0.508 0.5334)
			(layers "F.Cu" "F.Mask" "F.Paste")
			(net "12N3057")
		)
		(zone
			(layer "F.Cu")
			(hatch none 0.5)
			(connect_pads
				(clearance 0)
			)
			(min_thickness 0.25)
			(keepout
				(tracks not_allowed)
				(vias allowed)
				(pads allowed)
				(copperpour not_allowed)
				(footprints allowed)
			)
			(placement
				(enabled no)
				(sheetname "")
			)
			(fill
				(thermal_gap 0.5)
				(thermal_bridge_width 0.5)
				(island_removal_mode 0)
			)
			(polygon
				(pts
					(xy 78.8416 20.5486) (xy 78.8924 20.5486) (xy 78.8924 20.5994) (xy 78.8416 20.5994)
				)
			)
		)
	)
	(footprint ""
		(layer "F.Cu")
		(at 19.177 4.318 -90)
		(property "Reference" "C282"
			(at 0 0 270)
			(layer "F.SilkS")
			(hide yes)
			(effects
				(font
					(size 1.27 1.27)
				)
			)
		)
		(property "Value" "4.7UF"
			(at -0.091846 0.2921 0)
			(unlocked yes)
			(layer "F.Fab")
			(hide yes)
			(effects
				(font
					(size 0.7874 0.5842)
					(thickness 0.2032)
				)
				(justify left)
			)
		)
		(property "Device Type" "CAPC0065"
			(at -0.091846 0.2921 0)
			(unlocked yes)
			(layer "F.Fab")
			(hide yes)
			(effects
				(font
					(size 0.7874 0.5842)
					(thickness 0.2032)
				)
				(justify left)
			)
		)
		(duplicate_pad_numbers_are_jumpers no)
		(fp_poly
			(pts
				(xy 0.635 1.0668) (xy 0.635 -1.0668) (xy -0.635 -1.0668) (xy -0.635 1.0668)
			)
			(stroke
				(width 0)
				(type default)
			)
			(fill no)
			(layer "F.CrtYd")
		)
		(fp_line
			(start -0.254 0.508)
			(end -0.254 -0.508)
			(stroke
				(width 0.0254)
				(type default)
			)
			(layer "F.Fab")
		)
		(fp_line
			(start 0.254 0.508)
			(end -0.254 0.508)
			(stroke
				(width 0.0254)
				(type default)
			)
			(layer "F.Fab")
		)
		(fp_line
			(start -0.254 -0.508)
			(end 0.254 -0.508)
			(stroke
				(width 0.0254)
				(type default)
			)
			(layer "F.Fab")
		)
		(fp_line
			(start 0.254 -0.508)
			(end 0.254 0.508)
			(stroke
				(width 0.0254)
				(type default)
			)
			(layer "F.Fab")
		)
		(pad "1" smd rect
			(at 0 -0.4191 270)
			(size 0.508 0.5334)
			(layers "F.Cu" "F.Mask" "F.Paste")
			(net "13N4321")
		)
		(pad "2" smd rect
			(at 0 0.4191 270)
			(size 0.508 0.5334)
			(layers "F.Cu" "F.Mask" "F.Paste")
			(net "GND")
		)
		(zone
			(layer "F.Cu")
			(hatch none 0.5)
			(connect_pads
				(clearance 0)
			)
			(min_thickness 0.25)
			(keepout
				(tracks not_allowed)
				(vias allowed)
				(pads allowed)
				(copperpour not_allowed)
				(footprints allowed)
			)
			(placement
				(enabled no)
				(sheetname "")
			)
			(fill
				(thermal_gap 0.5)
				(thermal_bridge_width 0.5)
				(island_removal_mode 0)
			)
			(polygon
				(pts
					(xy 19.2024 4.3434) (xy 19.1516 4.3434) (xy 19.1516 4.2926) (xy 19.2024 4.2926)
				)
			)
		)
	)
	(footprint ""
		(layer "F.Cu")
		(at 25.908 39.497 -90)
		(property "Reference" "R323"
			(at 0 0 270)
			(layer "F.SilkS")
			(hide yes)
			(effects
				(font
					(size 1.27 1.27)
				)
			)
		)
		(property "Value" "4.02K"
			(at -0.148158 1.3462 0)
			(unlocked yes)
			(layer "F.Fab")
			(hide yes)
			(effects
				(font
					(size 1.27 0.9652)
					(thickness 0.000001)
				)
				(justify left)
			)
		)
		(property "Device Type" "REST0067"
			(at -0.148158 1.3462 0)
			(unlocked yes)
			(layer "F.Fab")
			(hide yes)
			(effects
				(font
					(size 1.27 0.9652)
					(thickness 0.000001)
				)
				(justify left)
			)
		)
		(duplicate_pad_numbers_are_jumpers no)
		(fp_poly
			(pts
				(xy 0.635 1.0668) (xy 0.635 -1.0668) (xy -0.635 -1.0668) (xy -0.635 1.0668)
			)
			(stroke
				(width 0)
				(type default)
			)
			(fill no)
			(layer "F.CrtYd")
		)
		(fp_line
			(start -0.254 0.508)
			(end -0.254 -0.508)
			(stroke
				(width 0.0254)
				(type default)
			)
			(layer "F.Fab")
		)
		(fp_line
			(start 0.254 0.508)
			(end -0.254 0.508)
			(stroke
				(width 0.0254)
				(type default)
			)
			(layer "F.Fab")
		)
		(fp_line
			(start -0.254 -0.508)
			(end 0.254 -0.508)
			(stroke
				(width 0.0254)
				(type default)
			)
			(layer "F.Fab")
		)
		(fp_line
			(start 0.254 -0.508)
			(end 0.254 0.508)
			(stroke
				(width 0.0254)
				(type default)
			)
			(layer "F.Fab")
		)
		(pad "1" smd rect
			(at 0 -0.4191 270)
			(size 0.508 0.5334)
			(layers "F.Cu" "F.Mask" "F.Paste")
			(net "NFP_VDD_CORE_IMON")
		)
		(pad "2" smd rect
			(at 0 0.4191 270)
			(size 0.508 0.5334)
			(layers "F.Cu" "F.Mask" "F.Paste")
			(net "NFP_VDD_CORE_SENSE_VSS")
		)
		(zone
			(layer "F.Cu")
			(hatch none 0.5)
			(connect_pads
				(clearance 0)
			)
			(min_thickness 0.25)
			(keepout
				(tracks not_allowed)
				(vias allowed)
				(pads allowed)
				(copperpour not_allowed)
				(footprints allowed)
			)
			(placement
				(enabled no)
				(sheetname "")
			)
			(fill
				(thermal_gap 0.5)
				(thermal_bridge_width 0.5)
				(island_removal_mode 0)
			)
			(polygon
				(pts
					(xy 25.9334 39.5224) (xy 25.8826 39.5224) (xy 25.8826 39.4716) (xy 25.9334 39.4716)
				)
			)
		)
	)
	(footprint ""
		(layer "F.Cu")
		(at 35.941 6.35 90)
		(property "Reference" "R133"
			(at 0 0 90)
			(layer "F.SilkS")
			(hide yes)
			(effects
				(font
					(size 1.27 1.27)
				)
			)
		)
		(property "Value" "0"
			(at -0.148158 1.3462 180)
			(unlocked yes)
			(layer "F.Fab")
			(hide yes)
			(effects
				(font
					(size 1.27 0.9652)
					(thickness 0.000001)
				)
				(justify left)
			)
		)
		(property "Device Type" "REST1111"
			(at -0.148158 1.3462 180)
			(unlocked yes)
			(layer "F.Fab")
			(hide yes)
			(effects
				(font
					(size 1.27 0.9652)
					(thickness 0.000001)
				)
				(justify left)
			)
		)
		(duplicate_pad_numbers_are_jumpers no)
		(fp_poly
			(pts
				(xy 0.635 1.0668) (xy 0.635 -1.0668) (xy -0.635 -1.0668) (xy -0.635 1.0668)
			)
			(stroke
				(width 0)
				(type default)
			)
			(fill no)
			(layer "F.CrtYd")
		)
		(fp_line
			(start 0.254 -0.508)
			(end 0.254 0.508)
			(stroke
				(width 0.0254)
				(type default)
			)
			(layer "F.Fab")
		)
		(fp_line
			(start -0.254 -0.508)
			(end 0.254 -0.508)
			(stroke
				(width 0.0254)
				(type default)
			)
			(layer "F.Fab")
		)
		(fp_line
			(start 0.254 0.508)
			(end -0.254 0.508)
			(stroke
				(width 0.0254)
				(type default)
			)
			(layer "F.Fab")
		)
		(fp_line
			(start -0.254 0.508)
			(end -0.254 -0.508)
			(stroke
				(width 0.0254)
				(type default)
			)
			(layer "F.Fab")
		)
		(pad "1" smd rect
			(at 0 -0.4191 90)
			(size 0.508 0.5334)
			(layers "F.Cu" "F.Mask" "F.Paste")
			(net "3N2291")
		)
		(pad "2" smd rect
			(at 0 0.4191 90)
			(size 0.508 0.5334)
			(layers "F.Cu" "F.Mask" "F.Paste")
			(net "NFP_SERDES012_SYSCLK_IN_P")
		)
		(zone
			(layer "F.Cu")
			(hatch none 0.5)
			(connect_pads
				(clearance 0)
			)
			(min_thickness 0.25)
			(keepout
				(tracks not_allowed)
				(vias allowed)
				(pads allowed)
				(copperpour not_allowed)
				(footprints allowed)
			)
			(placement
				(enabled no)
				(sheetname "")
			)
			(fill
				(thermal_gap 0.5)
				(thermal_bridge_width 0.5)
				(island_removal_mode 0)
			)
			(polygon
				(pts
					(xy 35.9156 6.3246) (xy 35.9664 6.3246) (xy 35.9664 6.3754) (xy 35.9156 6.3754)
				)
			)
		)
	)
	(footprint ""
		(layer "F.Cu")
		(at 23.749 35.687 180)
		(property "Reference" "R66"
			(at 0 0 180)
			(layer "F.SilkS")
			(hide yes)
			(effects
				(font
					(size 1.27 1.27)
				)
			)
		)
		(property "Value" "4.75K"
			(at -0.148158 1.3462 270)
			(unlocked yes)
			(layer "F.Fab")
			(hide yes)
			(effects
				(font
					(size 1.27 0.9652)
					(thickness 0.000001)
				)
				(justify left)
			)
		)
		(property "Device Type" "REST4024"
			(at -0.148158 1.3462 270)
			(unlocked yes)
			(layer "F.Fab")
			(hide yes)
			(effects
				(font
					(size 1.27 0.9652)
					(thickness 0.000001)
				)
				(justify left)
			)
		)
		(duplicate_pad_numbers_are_jumpers no)
		(fp_poly
			(pts
				(xy 0.635 1.0668) (xy 0.635 -1.0668) (xy -0.635 -1.0668) (xy -0.635 1.0668)
			)
			(stroke
				(width 0)
				(type default)
			)
			(fill no)
			(layer "F.CrtYd")
		)
		(fp_line
			(start 0.254 0.508)
			(end -0.254 0.508)
			(stroke
				(width 0.0254)
				(type default)
			)
			(layer "F.Fab")
		)
		(fp_line
			(start 0.254 -0.508)
			(end 0.254 0.508)
			(stroke
				(width 0.0254)
				(type default)
			)
			(layer "F.Fab")
		)
		(fp_line
			(start -0.254 0.508)
			(end -0.254 -0.508)
			(stroke
				(width 0.0254)
				(type default)
			)
			(layer "F.Fab")
		)
		(fp_line
			(start -0.254 -0.508)
			(end 0.254 -0.508)
			(stroke
				(width 0.0254)
				(type default)
			)
			(layer "F.Fab")
		)
		(pad "1" smd rect
			(at 0 -0.4191 180)
			(size 0.508 0.5334)
			(layers "F.Cu" "F.Mask" "F.Paste")
			(net "VDD_3.3V")
		)
		(pad "2" smd rect
			(at 0 0.4191 180)
			(size 0.508 0.5334)
			(layers "F.Cu" "F.Mask" "F.Paste")
			(net "NFP_CPLD_PRGM_JTAG_TMS")
		)
		(zone
			(layer "F.Cu")
			(hatch none 0.5)
			(connect_pads
				(clearance 0)
			)
			(min_thickness 0.25)
			(keepout
				(tracks not_allowed)
				(vias allowed)
				(pads allowed)
				(copperpour not_allowed)
				(footprints allowed)
			)
			(placement
				(enabled no)
				(sheetname "")
			)
			(fill
				(thermal_gap 0.5)
				(thermal_bridge_width 0.5)
				(island_removal_mode 0)
			)
			(polygon
				(pts
					(xy 23.7236 35.7124) (xy 23.7236 35.6616) (xy 23.7744 35.6616) (xy 23.7744 35.7124)
				)
			)
		)
	)
	(footprint ""
		(layer "F.Cu")
		(at 49.53 48.26)
		(property "Reference" "R102"
			(at 0 0 0)
			(layer "F.SilkS")
			(hide yes)
			(effects
				(font
					(size 1.27 1.27)
				)
			)
		)
		(property "Value" "4.75K"
			(at -0.148158 1.3462 90)
			(unlocked yes)
			(layer "F.Fab")
			(hide yes)
			(effects
				(font
					(size 1.27 0.9652)
					(thickness 0.000001)
				)
				(justify left)
			)
		)
		(property "Device Type" "REST4024"
			(at -0.148158 1.3462 90)
			(unlocked yes)
			(layer "F.Fab")
			(hide yes)
			(effects
				(font
					(size 1.27 0.9652)
					(thickness 0.000001)
				)
				(justify left)
			)
		)
		(duplicate_pad_numbers_are_jumpers no)
		(fp_poly
			(pts
				(xy 0.635 1.0668) (xy 0.635 -1.0668) (xy -0.635 -1.0668) (xy -0.635 1.0668)
			)
			(stroke
				(width 0)
				(type default)
			)
			(fill no)
			(layer "F.CrtYd")
		)
		(fp_line
			(start -0.254 -0.508)
			(end 0.254 -0.508)
			(stroke
				(width 0.0254)
				(type default)
			)
			(layer "F.Fab")
		)
		(fp_line
			(start -0.254 0.508)
			(end -0.254 -0.508)
			(stroke
				(width 0.0254)
				(type default)
			)
			(layer "F.Fab")
		)
		(fp_line
			(start 0.254 -0.508)
			(end 0.254 0.508)
			(stroke
				(width 0.0254)
				(type default)
			)
			(layer "F.Fab")
		)
		(fp_line
			(start 0.254 0.508)
			(end -0.254 0.508)
			(stroke
				(width 0.0254)
				(type default)
			)
			(layer "F.Fab")
		)
		(pad "1" smd rect
			(at 0 -0.4191)
			(size 0.508 0.5334)
			(layers "F.Cu" "F.Mask" "F.Paste")
			(net "GND")
		)
		(pad "2" smd rect
			(at 0 0.4191)
			(size 0.508 0.5334)
			(layers "F.Cu" "F.Mask" "F.Paste")
			(net "EXT_3.3V_PGOOD")
		)
		(zone
			(layer "F.Cu")
			(hatch none 0.5)
			(connect_pads
				(clearance 0)
			)
			(min_thickness 0.25)
			(keepout
				(tracks not_allowed)
				(vias allowed)
				(pads allowed)
				(copperpour not_allowed)
				(footprints allowed)
			)
			(placement
				(enabled no)
				(sheetname "")
			)
			(fill
				(thermal_gap 0.5)
				(thermal_bridge_width 0.5)
				(island_removal_mode 0)
			)
			(polygon
				(pts
					(xy 49.5554 48.2346) (xy 49.5554 48.2854) (xy 49.5046 48.2854) (xy 49.5046 48.2346)
				)
			)
		)
	)
)
